(kicad_pcb
	(version 20260206)
	(generator "pcbnew")
	(generator_version "10.0")
	(general
		(thickness 1.6)
		(legacy_teardrops no)
	)
	(paper "A4")
	(title_block
		(title "timecard-production-celestica-r4006 — R4006-B0001-02_R01.brd")
		(comment 1 "Time Appliance Project (Time Card) / footprints 384-390 of 1113")
	)
	(layers
		(0 "F.Cu" signal "TOP")
		(4 "In1.Cu" signal "L02_GND1")
		(6 "In2.Cu" signal "L03_SIG1")
		(8 "In3.Cu" signal "L04_GND2")
		(10 "In4.Cu" signal "L05_VCC1")
		(12 "In5.Cu" signal "L06_VCC2")
		(14 "In6.Cu" signal "L07_GND3")
		(16 "In7.Cu" signal "L08_SIG2")
		(18 "In8.Cu" signal "L09_GND4")
		(2 "B.Cu" signal "BOTTOM")
		(9 "F.Adhes" user "F.Adhesive")
		(11 "B.Adhes" user "B.Adhesive")
		(13 "F.Paste" user "Package Geometry/Pastemask Top")
		(15 "B.Paste" user "Package Geometry/Pastemask Bottom")
		(5 "F.SilkS" user "Ref Des/Silkscreen Top")
		(7 "B.SilkS" user "Ref Des/Silkscreen Bottom")
		(1 "F.Mask" user "Board Geometry/Soldermask Top")
		(3 "B.Mask" user "Board Geometry/Soldermask Bottom")
		(17 "Dwgs.User" user "User.Drawings")
		(19 "Cmts.User" user "User.Comments")
		(21 "Eco1.User" user "User.Eco1")
		(23 "Eco2.User" user "User.Eco2")
		(25 "Edge.Cuts" user "Board Geometry/Outline")
		(27 "Margin" user)
		(31 "F.CrtYd" user "Package Geometry/Place Bound Top")
		(29 "B.CrtYd" user "Package Geometry/Place Bound Bottom")
		(35 "F.Fab" user "Ref Des/Assembly Top")
		(33 "B.Fab" user "Ref Des/Assembly Bottom")
	)
	(footprint ""
		(layer "F.Cu")
		(at 106.9086 -64.2874 -90)
		(property "Reference" "R325"
			(at 0.0254 -2.22377 90)
			(unlocked yes)
			(layer "F.SilkS")
			(effects
				(font
					(size 0.7874 0.5842)
					(thickness 0.1524)
				)
			)
		)
		(property "Value" "VAL*"
			(at 0.02032 2.13233 270)
			(unlocked yes)
			(layer "F.Fab")
			(hide yes)
			(effects
				(font
					(size 0.7874 0.5842)
					(thickness 0.1524)
				)
			)
		)
		(property "Tolerance" "TOL*"
			(at 0.044704 3.05435 270)
			(unlocked yes)
			(layer "Cmts.User")
			(hide yes)
			(effects
				(font
					(size 0.7874 0.5842)
					(thickness 0.1524)
				)
			)
		)
		(property "User Part Number" "PARTNUM*"
			(at 0.02032 4.024884 270)
			(unlocked yes)
			(layer "Cmts.User")
			(hide yes)
			(effects
				(font
					(size 0.7874 0.5842)
					(thickness 0.1524)
				)
			)
		)
		(property "Device Type" "RESISTOR-G155-11002-01,10KOHM,A"
			(at 0.008382 1.210564 270)
			(unlocked yes)
			(layer "F.Fab")
			(hide yes)
			(effects
				(font
					(size 0.7874 0.5842)
					(thickness 0.1524)
				)
			)
		)
		(duplicate_pad_numbers_are_jumpers no)
		(fp_line
			(start -1.143 0.5588)
			(end 1.143 0.5588)
			(stroke
				(width 0.1)
				(type default)
			)
			(layer "F.SilkS")
		)
		(fp_line
			(start 1.143 0.5588)
			(end 1.143 -0.5588)
			(stroke
				(width 0.1)
				(type default)
			)
			(layer "F.SilkS")
		)
		(fp_line
			(start -1.143 -0.5588)
			(end -1.143 0.5588)
			(stroke
				(width 0.1)
				(type default)
			)
			(layer "F.SilkS")
		)
		(fp_line
			(start 1.143 -0.5588)
			(end -1.143 -0.5588)
			(stroke
				(width 0.1)
				(type default)
			)
			(layer "F.SilkS")
		)
		(fp_poly
			(pts
				(xy -1.143 0.5588) (xy 1.143 0.5588) (xy 1.143 -0.5588) (xy -1.143 -0.5588)
			)
			(stroke
				(width 0)
				(type default)
			)
			(fill no)
			(layer "F.CrtYd")
		)
		(fp_line
			(start -0.508 0.3048)
			(end 0.508 0.3048)
			(stroke
				(width 0.1)
				(type default)
			)
			(layer "F.Fab")
		)
		(fp_line
			(start 0.508 0.3048)
			(end 0.508 -0.3048)
			(stroke
				(width 0.1)
				(type default)
			)
			(layer "F.Fab")
		)
		(fp_line
			(start -0.508 -0.3048)
			(end -0.508 0.3048)
			(stroke
				(width 0.1)
				(type default)
			)
			(layer "F.Fab")
		)
		(fp_line
			(start 0.508 -0.3048)
			(end -0.508 -0.3048)
			(stroke
				(width 0.1)
				(type default)
			)
			(layer "F.Fab")
		)
		(pad "1" smd rect
			(at -0.5334 0 270)
			(size 0.7112 0.6096)
			(layers "F.Cu" "F.Mask" "F.Paste")
			(net "XP3R3V_FPGA")
		)
		(pad "2" smd rect
			(at 0.5334 0 270)
			(size 0.7112 0.6096)
			(layers "F.Cu" "F.Mask" "F.Paste")
			(net "FPGA_IO_6")
		)
		(zone
			(layer "F.Cu")
			(hatch none 0.5)
			(connect_pads
				(clearance 0)
			)
			(min_thickness 0.25)
			(keepout
				(tracks allowed)
				(vias not_allowed)
				(pads allowed)
				(copperpour not_allowed)
				(footprints allowed)
			)
			(placement
				(enabled no)
				(sheetname "")
			)
			(fill
				(thermal_gap 0.5)
				(thermal_bridge_width 0.5)
				(island_removal_mode 0)
			)
			(polygon
				(pts
					(xy 106.6038 -64.3636) (xy 106.6038 -64.2112) (xy 107.2134 -64.2112) (xy 107.2134 -64.3636)
				)
			)
		)
		(zone
			(layer "F.Cu")
			(hatch none 0.5)
			(connect_pads
				(clearance 0)
			)
			(min_thickness 0.25)
			(keepout
				(tracks not_allowed)
				(vias allowed)
				(pads allowed)
				(copperpour not_allowed)
				(footprints allowed)
			)
			(placement
				(enabled no)
				(sheetname "")
			)
			(fill
				(thermal_gap 0.5)
				(thermal_bridge_width 0.5)
				(island_removal_mode 0)
			)
			(polygon
				(pts
					(xy 106.6038 -64.3636) (xy 106.6038 -64.2112) (xy 107.2134 -64.2112) (xy 107.2134 -64.3636)
				)
			)
		)
	)
	(footprint ""
		(layer "F.Cu")
		(at 139.8524 -90.6526 180)
		(property "Reference" "FU1"
			(at 2.4384 -0.39497 0)
			(unlocked yes)
			(layer "F.SilkS")
			(effects
				(font
					(size 0.7874 0.5842)
					(thickness 0.1524)
				)
			)
		)
		(property "Value" "VAL*"
			(at 0.0508 2.549906 180)
			(unlocked yes)
			(layer "F.Fab")
			(hide yes)
			(effects
				(font
					(size 0.7874 0.5842)
					(thickness 0.1524)
				)
			)
		)
		(property "Device Type" "FUSE-G280-10012-01,2.5A"
			(at 0.0254 1.584706 180)
			(unlocked yes)
			(layer "F.Fab")
			(hide yes)
			(effects
				(font
					(size 0.7874 0.5842)
					(thickness 0.1524)
				)
			)
		)
		(property "User Part Number" "PARTNUM*"
			(at 0.0762 4.480306 180)
			(unlocked yes)
			(layer "Cmts.User")
			(hide yes)
			(effects
				(font
					(size 0.7874 0.5842)
					(thickness 0.1524)
				)
			)
		)
		(property "Tolerance" "TOL*"
			(at 0.0508 3.515106 180)
			(unlocked yes)
			(layer "Cmts.User")
			(hide yes)
			(effects
				(font
					(size 0.7874 0.5842)
					(thickness 0.1524)
				)
			)
		)
		(duplicate_pad_numbers_are_jumpers no)
		(fp_line
			(start 1.3208 0.7112)
			(end -1.3208 0.7112)
			(stroke
				(width 0.1)
				(type default)
			)
			(layer "F.SilkS")
		)
		(fp_line
			(start 1.3208 -0.7112)
			(end 1.3208 0.7112)
			(stroke
				(width 0.1)
				(type default)
			)
			(layer "F.SilkS")
		)
		(fp_line
			(start -1.3208 0.7112)
			(end -1.3208 -0.7112)
			(stroke
				(width 0.1)
				(type default)
			)
			(layer "F.SilkS")
		)
		(fp_line
			(start -1.3208 -0.7112)
			(end 1.3208 -0.7112)
			(stroke
				(width 0.1)
				(type default)
			)
			(layer "F.SilkS")
		)
		(fp_rect
			(start 1.3208 -0.7112)
			(end -1.3208 0.7112)
			(stroke
				(width 0)
				(type default)
			)
			(fill no)
			(layer "F.CrtYd")
		)
		(fp_line
			(start 0.8128 0.4572)
			(end -0.8128 0.4572)
			(stroke
				(width 0.1)
				(type default)
			)
			(layer "F.Fab")
		)
		(fp_line
			(start 0.8128 -0.4572)
			(end 0.8128 0.4572)
			(stroke
				(width 0.1)
				(type default)
			)
			(layer "F.Fab")
		)
		(fp_line
			(start -0.8128 0.4572)
			(end -0.8128 -0.4572)
			(stroke
				(width 0.1)
				(type default)
			)
			(layer "F.Fab")
		)
		(fp_line
			(start -0.8128 -0.4572)
			(end 0.8128 -0.4572)
			(stroke
				(width 0.1)
				(type default)
			)
			(layer "F.Fab")
		)
		(pad "1" smd rect
			(at -0.6858 0 180)
			(size 0.762 0.8636)
			(layers "F.Cu" "F.Mask" "F.Paste")
			(net "XP12R0V_IN")
		)
		(pad "2" smd rect
			(at 0.6858 0 180)
			(size 0.762 0.8636)
			(layers "F.Cu" "F.Mask" "F.Paste")
			(net "XP12R0V")
		)
		(zone
			(layer "F.Cu")
			(hatch none 0.5)
			(connect_pads
				(clearance 0)
			)
			(min_thickness 0.25)
			(keepout
				(tracks allowed)
				(vias not_allowed)
				(pads allowed)
				(copperpour not_allowed)
				(footprints allowed)
			)
			(placement
				(enabled no)
				(sheetname "")
			)
			(fill
				(thermal_gap 0.5)
				(thermal_bridge_width 0.5)
				(island_removal_mode 0)
			)
			(polygon
				(pts
					(xy 139.7 -90.1954) (xy 140.0048 -90.1954) (xy 140.0048 -91.1098) (xy 139.7 -91.1098)
				)
			)
		)
	)
	(footprint ""
		(layer "F.Cu")
		(at 52.451 -131.699)
		(property "Reference" "SP33"
			(at 0 0 0)
			(layer "F.SilkS")
			(hide yes)
			(effects
				(font
					(size 1.27 1.27)
				)
			)
		)
		(property "Value" ""
			(at 0 0 0)
			(layer "F.Fab")
			(effects
				(font
					(size 1.27 1.27)
				)
			)
		)
		(duplicate_pad_numbers_are_jumpers no)
	)
	(footprint ""
		(layer "F.Cu")
		(at 115.443 -73.533)
		(property "Reference" "C235"
			(at 3.302 0.42037 0)
			(unlocked yes)
			(layer "F.SilkS")
			(effects
				(font
					(size 0.7874 0.5842)
					(thickness 0.1524)
				)
			)
		)
		(property "Value" "VAL*"
			(at 0.0762 2.067306 0)
			(unlocked yes)
			(layer "F.Fab")
			(hide yes)
			(effects
				(font
					(size 0.7874 0.5842)
					(thickness 0.1524)
				)
			)
		)
		(property "Tolerance" "TOL*"
			(at 0.0762 3.032506 0)
			(unlocked yes)
			(layer "Cmts.User")
			(hide yes)
			(effects
				(font
					(size 0.7874 0.5842)
					(thickness 0.1524)
				)
			)
		)
		(property "User Part Number" "PARTNUM*"
			(at 0.1016 4.023106 0)
			(unlocked yes)
			(layer "Cmts.User")
			(hide yes)
			(effects
				(font
					(size 0.7874 0.5842)
					(thickness 0.1524)
				)
			)
		)
		(property "Device Type" "CAPACITOR-G105-0B104-CK,0.1UF,A"
			(at 0.0508 1.127506 0)
			(unlocked yes)
			(layer "F.Fab")
			(hide yes)
			(effects
				(font
					(size 0.7874 0.5842)
					(thickness 0.1524)
				)
			)
		)
		(duplicate_pad_numbers_are_jumpers no)
		(fp_line
			(start -1.143 -0.5588)
			(end -1.143 0.5588)
			(stroke
				(width 0.1)
				(type default)
			)
			(layer "F.SilkS")
		)
		(fp_line
			(start -1.143 0.5588)
			(end 1.143 0.5588)
			(stroke
				(width 0.1)
				(type default)
			)
			(layer "F.SilkS")
		)
		(fp_line
			(start 1.143 -0.5588)
			(end -1.143 -0.5588)
			(stroke
				(width 0.1)
				(type default)
			)
			(layer "F.SilkS")
		)
		(fp_line
			(start 1.143 0.5588)
			(end 1.143 -0.5588)
			(stroke
				(width 0.1)
				(type default)
			)
			(layer "F.SilkS")
		)
		(fp_rect
			(start 1.143 0.5588)
			(end -1.143 -0.5588)
			(stroke
				(width 0)
				(type default)
			)
			(fill no)
			(layer "F.CrtYd")
		)
		(fp_line
			(start -0.508 -0.3048)
			(end -0.508 0.3048)
			(stroke
				(width 0.1)
				(type default)
			)
			(layer "F.Fab")
		)
		(fp_line
			(start -0.508 0.3048)
			(end 0.508 0.3048)
			(stroke
				(width 0.1)
				(type default)
			)
			(layer "F.Fab")
		)
		(fp_line
			(start 0.508 -0.3048)
			(end -0.508 -0.3048)
			(stroke
				(width 0.1)
				(type default)
			)
			(layer "F.Fab")
		)
		(fp_line
			(start 0.508 0.3048)
			(end 0.508 -0.3048)
			(stroke
				(width 0.1)
				(type default)
			)
			(layer "F.Fab")
		)
		(pad "1" smd rect
			(at -0.5334 0)
			(size 0.7112 0.6096)
			(layers "F.Cu" "F.Mask" "F.Paste")
			(net "XP3R3V")
		)
		(pad "2" smd rect
			(at 0.5334 0)
			(size 0.7112 0.6096)
			(layers "F.Cu" "F.Mask" "F.Paste")
			(net "SG")
		)
		(zone
			(layer "F.Cu")
			(hatch none 0.5)
			(connect_pads
				(clearance 0)
			)
			(min_thickness 0.25)
			(keepout
				(tracks allowed)
				(vias not_allowed)
				(pads allowed)
				(copperpour not_allowed)
				(footprints allowed)
			)
			(placement
				(enabled no)
				(sheetname "")
			)
			(fill
				(thermal_gap 0.5)
				(thermal_bridge_width 0.5)
				(island_removal_mode 0)
			)
			(polygon
				(pts
					(xy 115.5192 -73.2282) (xy 115.5192 -73.8378) (xy 115.3668 -73.8378) (xy 115.3668 -73.2282)
				)
			)
		)
	)
	(footprint ""
		(layer "F.Cu")
		(at 14.605 -52.578 -90)
		(property "Reference" "R331"
			(at 0.508 3.51663 90)
			(unlocked yes)
			(layer "F.SilkS")
			(effects
				(font
					(size 0.7874 0.5842)
					(thickness 0.1524)
				)
			)
		)
		(property "Value" "VAL*"
			(at 0.02032 2.13233 270)
			(unlocked yes)
			(layer "F.Fab")
			(hide yes)
			(effects
				(font
					(size 0.7874 0.5842)
					(thickness 0.1524)
				)
			)
		)
		(property "Device Type" "RESISTOR-G155-14701-01,4.7KOHMA"
			(at 0.008382 1.210564 270)
			(unlocked yes)
			(layer "F.Fab")
			(hide yes)
			(effects
				(font
					(size 0.7874 0.5842)
					(thickness 0.1524)
				)
			)
		)
		(property "User Part Number" "PARTNUM*"
			(at 0.02032 4.024884 270)
			(unlocked yes)
			(layer "Cmts.User")
			(hide yes)
			(effects
				(font
					(size 0.7874 0.5842)
					(thickness 0.1524)
				)
			)
		)
		(property "Tolerance" "TOL*"
			(at 0.044704 3.05435 270)
			(unlocked yes)
			(layer "Cmts.User")
			(hide yes)
			(effects
				(font
					(size 0.7874 0.5842)
					(thickness 0.1524)
				)
			)
		)
		(duplicate_pad_numbers_are_jumpers no)
		(fp_line
			(start -1.143 0.5588)
			(end 1.143 0.5588)
			(stroke
				(width 0.1)
				(type default)
			)
			(layer "F.SilkS")
		)
		(fp_line
			(start 1.143 0.5588)
			(end 1.143 -0.5588)
			(stroke
				(width 0.1)
				(type default)
			)
			(layer "F.SilkS")
		)
		(fp_line
			(start -1.143 -0.5588)
			(end -1.143 0.5588)
			(stroke
				(width 0.1)
				(type default)
			)
			(layer "F.SilkS")
		)
		(fp_line
			(start 1.143 -0.5588)
			(end -1.143 -0.5588)
			(stroke
				(width 0.1)
				(type default)
			)
			(layer "F.SilkS")
		)
		(fp_rect
			(start 1.143 0.5588)
			(end -1.143 -0.5588)
			(stroke
				(width 0)
				(type default)
			)
			(fill no)
			(layer "F.CrtYd")
		)
		(fp_line
			(start -0.508 0.3048)
			(end 0.508 0.3048)
			(stroke
				(width 0.1)
				(type default)
			)
			(layer "F.Fab")
		)
		(fp_line
			(start 0.508 0.3048)
			(end 0.508 -0.3048)
			(stroke
				(width 0.1)
				(type default)
			)
			(layer "F.Fab")
		)
		(fp_line
			(start -0.508 -0.3048)
			(end -0.508 0.3048)
			(stroke
				(width 0.1)
				(type default)
			)
			(layer "F.Fab")
		)
		(fp_line
			(start 0.508 -0.3048)
			(end -0.508 -0.3048)
			(stroke
				(width 0.1)
				(type default)
			)
			(layer "F.Fab")
		)
		(pad "1" smd rect
			(at -0.5334 0 270)
			(size 0.7112 0.6096)
			(layers "F.Cu" "F.Mask" "F.Paste")
			(net "XP3R3V_FPGA")
		)
		(pad "2" smd rect
			(at 0.5334 0 270)
			(size 0.7112 0.6096)
			(layers "F.Cu" "F.Mask" "F.Paste")
			(net "SMA2_SIG_OUT_BF_EN_N")
		)
		(zone
			(layer "F.Cu")
			(hatch none 0.5)
			(connect_pads
				(clearance 0)
			)
			(min_thickness 0.25)
			(keepout
				(tracks allowed)
				(vias not_allowed)
				(pads allowed)
				(copperpour not_allowed)
				(footprints allowed)
			)
			(placement
				(enabled no)
				(sheetname "")
			)
			(fill
				(thermal_gap 0.5)
				(thermal_bridge_width 0.5)
				(island_removal_mode 0)
			)
			(polygon
				(pts
					(xy 14.3002 -52.5018) (xy 14.9098 -52.5018) (xy 14.9098 -52.6542) (xy 14.3002 -52.6542)
				)
			)
		)
	)
	(footprint ""
		(layer "F.Cu")
		(at 57.15 -100.584)
		(property "Reference" "TP60"
			(at 1.651 0.15367 0)
			(unlocked yes)
			(layer "F.SilkS")
			(effects
				(font
					(size 0.7874 0.5842)
					(thickness 0.1524)
				)
				(justify left)
			)
		)
		(property "Value" ""
			(at 0 0 0)
			(layer "F.Fab")
			(effects
				(font
					(size 1.27 1.27)
				)
			)
		)
		(property "Device Type" "TP_PIONT-TP010CT020B030_PTH-TPA"
			(at -1.341882 0.996696 0)
			(unlocked yes)
			(layer "F.Fab")
			(hide yes)
			(effects
				(font
					(size 0.7874 0.5842)
					(thickness 0.1524)
				)
				(justify left)
			)
		)
		(duplicate_pad_numbers_are_jumpers no)
		(fp_poly
			(pts
				(arc
					(start 0.889 0)
					(mid -0.889 0)
					(end 0.889 0)
				)
			)
			(stroke
				(width 0)
				(type default)
			)
			(fill no)
			(layer "B.CrtYd")
		)
		(fp_poly
			(pts
				(arc
					(start 0.889 0)
					(mid -0.889 0)
					(end 0.889 0)
				)
			)
			(stroke
				(width 0)
				(type default)
			)
			(fill no)
			(layer "F.CrtYd")
		)
		(pad "1" thru_hole circle
			(at 0 0)
			(size 0.508 0.508)
			(drill 0.254)
			(layers "*.Cu" "*.Mask")
			(remove_unused_layers no)
			(net "XP5R0V")
			(clearance 0.1016)
			(padstack
				(mode front_inner_back)
				(layer "Inner"
					(shape circle)
					(size 0.508 0.508)
					(clearance 0.1016)
				)
				(layer "B.Cu"
					(shape circle)
					(size 0.762 0.762)
					(clearance -0.0254)
				)
			)
		)
	)
	(footprint ""
		(layer "F.Cu")
		(at 110.3757 -28.5242 180)
		(property "Reference" "R360"
			(at 2.00533 -0.8382 90)
			(unlocked yes)
			(layer "F.SilkS")
			(effects
				(font
					(size 0.7874 0.5842)
					(thickness 0.1524)
				)
			)
		)
		(property "Value" "VAL*"
			(at 0.02032 2.13233 180)
			(unlocked yes)
			(layer "F.Fab")
			(hide yes)
			(effects
				(font
					(size 0.7874 0.5842)
					(thickness 0.1524)
				)
			)
		)
		(property "Tolerance" "TOL*"
			(at 0.044704 3.05435 180)
			(unlocked yes)
			(layer "Cmts.User")
			(hide yes)
			(effects
				(font
					(size 0.7874 0.5842)
					(thickness 0.1524)
				)
			)
		)
		(property "User Part Number" "PARTNUM*"
			(at 0.02032 4.024884 180)
			(unlocked yes)
			(layer "Cmts.User")
			(hide yes)
			(effects
				(font
					(size 0.7874 0.5842)
					(thickness 0.1524)
				)
			)
		)
		(property "Device Type" "RESISTOR-G155-11002-01,10KOHM,A"
			(at 0.008382 1.210564 180)
			(unlocked yes)
			(layer "F.Fab")
			(hide yes)
			(effects
				(font
					(size 0.7874 0.5842)
					(thickness 0.1524)
				)
			)
		)
		(duplicate_pad_numbers_are_jumpers no)
		(fp_line
			(start 1.143 0.5588)
			(end 1.143 -0.5588)
			(stroke
				(width 0.1)
				(type default)
			)
			(layer "F.SilkS")
		)
		(fp_line
			(start 1.143 -0.5588)
			(end -1.143 -0.5588)
			(stroke
				(width 0.1)
				(type default)
			)
			(layer "F.SilkS")
		)
		(fp_line
			(start -1.143 0.5588)
			(end 1.143 0.5588)
			(stroke
				(width 0.1)
				(type default)
			)
			(layer "F.SilkS")
		)
		(fp_line
			(start -1.143 -0.5588)
			(end -1.143 0.5588)
			(stroke
				(width 0.1)
				(type default)
			)
			(layer "F.SilkS")
		)
		(fp_poly
			(pts
				(xy -1.143 0.5588) (xy 1.143 0.5588) (xy 1.143 -0.5588) (xy -1.143 -0.5588)
			)
			(stroke
				(width 0)
				(type default)
			)
			(fill no)
			(layer "F.CrtYd")
		)
		(fp_line
			(start 0.508 0.3048)
			(end 0.508 -0.3048)
			(stroke
				(width 0.1)
				(type default)
			)
			(layer "F.Fab")
		)
		(fp_line
			(start 0.508 -0.3048)
			(end -0.508 -0.3048)
			(stroke
				(width 0.1)
				(type default)
			)
			(layer "F.Fab")
		)
		(fp_line
			(start -0.508 0.3048)
			(end 0.508 0.3048)
			(stroke
				(width 0.1)
				(type default)
			)
			(layer "F.Fab")
		)
		(fp_line
			(start -0.508 -0.3048)
			(end -0.508 0.3048)
			(stroke
				(width 0.1)
				(type default)
			)
			(layer "F.Fab")
		)
		(pad "1" smd rect
			(at -0.5334 0 180)
			(size 0.7112 0.6096)
			(layers "F.Cu" "F.Mask" "F.Paste")
			(net "MHZ200CLKN_CLKIN")
		)
		(pad "2" smd rect
			(at 0.5334 0 180)
			(size 0.7112 0.6096)
			(layers "F.Cu" "F.Mask" "F.Paste")
			(net "SG")
		)
		(zone
			(layer "F.Cu")
			(hatch none 0.5)
			(connect_pads
				(clearance 0)
			)
			(min_thickness 0.25)
			(keepout
				(tracks not_allowed)
				(vias allowed)
				(pads allowed)
				(copperpour not_allowed)
				(footprints allowed)
			)
			(placement
				(enabled no)
				(sheetname "")
			)
			(fill
				(thermal_gap 0.5)
				(thermal_bridge_width 0.5)
				(island_removal_mode 0)
			)
			(polygon
				(pts
					(xy 110.4519 -28.829) (xy 110.2995 -28.829) (xy 110.2995 -28.2194) (xy 110.4519 -28.2194)
				)
			)
		)
		(zone
			(layer "F.Cu")
			(hatch none 0.5)
			(connect_pads
				(clearance 0)
			)
			(min_thickness 0.25)
			(keepout
				(tracks allowed)
				(vias not_allowed)
				(pads allowed)
				(copperpour not_allowed)
				(footprints allowed)
			)
			(placement
				(enabled no)
				(sheetname "")
			)
			(fill
				(thermal_gap 0.5)
				(thermal_bridge_width 0.5)
				(island_removal_mode 0)
			)
			(polygon
				(pts
					(xy 110.4519 -28.829) (xy 110.2995 -28.829) (xy 110.2995 -28.2194) (xy 110.4519 -28.2194)
				)
			)
		)
	)
)
